# S9S_MB_2U (Grand Teton) — schematic parts with pin connectivity, parts 3106–3120 of 6093; source: Cadence DE-HDL packaged netlist (pstxprt.dat, pstxnet.dat, pstchip.dat)

PU24_P1_7  ISL99390FRZTR5935  ISL99390FRZ-TR5935 IC  pkg QFN21_6X5XB  page 288
  1  VOS  IN  = PVCCIN_CPU1_VOS7
  2  AGND  POWER  = GND
  3  VCC  POWER  = PVCCIN_CPU1_VDD7
  4  PVCC  POWER  = PVCCIN_CPU1_PVCC
  5  PGND1  POWER  = GND
  6  GL1  OUT  = NC
  7_9-20_24  PGND2  POWER  = GND
  10_19  SW  OUT  = SW_PVCCIN_CPU1_SW7
  25_29  VIN1  IN  = SW_P12V_PVCCIN_CPU1_FLT
  30  VIN2  IN  = SW_P12V_PVCCIN_CPU1_FLT
  31  DNC  TRI  = NC
  32  PHASE  POWER  = SW_PVCCIN_CPU1_BOOTR7
  33  BOOT  POWER  = SW_PVCCIN_CPU1_BOOT7
  34  PWM  IN  = PVCCIN_CPU1_PWM7
  35  EN  IN  = PVCCIN_CPU1_VDD7
  36  TOUT_FLT  OUT  = PVCCIN_CPU1_ATSEN
  37  LSET  OUT  = PVCCIN_CPU1_LSET7
  38  IOUT  OUT  = PVCCIN_CPU1_IMON7
  39  REFIN  IN  = PVCCIN_CPU1_VREF
  40  PGND3  POWER  = GND
  41  GL2  OUT  = NC

PU25_P1_6  ISL99390FRZTR5935  ISL99390FRZ-TR5935 IC  pkg QFN21_6X5XB  page 287
  1  VOS  IN  = PVCCIN_CPU1_VOS6
  2  AGND  POWER  = GND
  3  VCC  POWER  = PVCCIN_CPU1_VDD6
  4  PVCC  POWER  = PVCCIN_CPU1_PVCC
  5  PGND1  POWER  = GND
  6  GL1  OUT  = NC
  7_9-20_24  PGND2  POWER  = GND
  10_19  SW  OUT  = SW_PVCCIN_CPU1_SW6
  25_29  VIN1  IN  = SW_P12V_PVCCIN_CPU1_FLT
  30  VIN2  IN  = SW_P12V_PVCCIN_CPU1_FLT
  31  DNC  TRI  = NC
  32  PHASE  POWER  = SW_PVCCIN_CPU1_BOOTR6
  33  BOOT  POWER  = SW_PVCCIN_CPU1_BOOT6
  34  PWM  IN  = PVCCIN_CPU1_PWM6
  35  EN  IN  = PVCCIN_CPU1_VDD6
  36  TOUT_FLT  OUT  = PVCCIN_CPU1_ATSEN
  37  LSET  OUT  = PVCCIN_CPU1_LSET6
  38  IOUT  OUT  = PVCCIN_CPU1_IMON6
  39  REFIN  IN  = PVCCIN_CPU1_VREF
  40  PGND3  POWER  = GND
  41  GL2  OUT  = NC

PU26_P1_5  ISL99390FRZTR5935  ISL99390FRZ-TR5935 IC  pkg QFN21_6X5XB  page 287
  1  VOS  IN  = PVCCIN_CPU1_VOS5
  2  AGND  POWER  = GND
  3  VCC  POWER  = PVCCIN_CPU1_VDD5
  4  PVCC  POWER  = PVCCIN_CPU1_PVCC
  5  PGND1  POWER  = GND
  6  GL1  OUT  = NC
  7_9-20_24  PGND2  POWER  = GND
  10_19  SW  OUT  = SW_PVCCIN_CPU1_SW5
  25_29  VIN1  IN  = SW_P12V_PVCCIN_CPU1_FLT
  30  VIN2  IN  = SW_P12V_PVCCIN_CPU1_FLT
  31  DNC  TRI  = NC
  32  PHASE  POWER  = SW_PVCCIN_CPU1_BOOTR5
  33  BOOT  POWER  = SW_PVCCIN_CPU1_BOOT5
  34  PWM  IN  = PVCCIN_CPU1_PWM5
  35  EN  IN  = PVCCIN_CPU1_VDD5
  36  TOUT_FLT  OUT  = PVCCIN_CPU1_ATSEN
  37  LSET  OUT  = PVCCIN_CPU1_LSET5
  38  IOUT  OUT  = PVCCIN_CPU1_IMON5
  39  REFIN  IN  = PVCCIN_CPU1_VREF
  40  PGND3  POWER  = GND
  41  GL2  OUT  = NC

PU27_P1_4  ISL99390FRZTR5935  ISL99390FRZ-TR5935 IC  pkg QFN21_6X5XB  page 286
  1  VOS  IN  = PVCCIN_CPU1_VOS4
  2  AGND  POWER  = GND
  3  VCC  POWER  = PVCCIN_CPU1_VDD4
  4  PVCC  POWER  = PVCCIN_CPU1_PVCC
  5  PGND1  POWER  = GND
  6  GL1  OUT  = NC
  7_9-20_24  PGND2  POWER  = GND
  10_19  SW  OUT  = SW_PVCCIN_CPU1_SW4
  25_29  VIN1  IN  = SW_P12V_PVCCIN_CPU1_FLT
  30  VIN2  IN  = SW_P12V_PVCCIN_CPU1_FLT
  31  DNC  TRI  = NC
  32  PHASE  POWER  = SW_PVCCIN_CPU1_BOOTR4
  33  BOOT  POWER  = SW_PVCCIN_CPU1_BOOT4
  34  PWM  IN  = PVCCIN_CPU1_PWM4
  35  EN  IN  = PVCCIN_CPU1_VDD4
  36  TOUT_FLT  OUT  = PVCCIN_CPU1_ATSEN
  37  LSET  OUT  = PVCCIN_CPU1_LSET4
  38  IOUT  OUT  = PVCCIN_CPU1_IMON4
  39  REFIN  IN  = PVCCIN_CPU1_VREF
  40  PGND3  POWER  = GND
  41  GL2  OUT  = NC

PU28_P1_3  ISL99390FRZTR5935  ISL99390FRZ-TR5935 IC  pkg QFN21_6X5XB  page 286
  1  VOS  IN  = PVCCIN_CPU1_VOS3
  2  AGND  POWER  = GND
  3  VCC  POWER  = PVCCIN_CPU1_VDD3
  4  PVCC  POWER  = PVCCIN_CPU1_PVCC
  5  PGND1  POWER  = GND
  6  GL1  OUT  = NC
  7_9-20_24  PGND2  POWER  = GND
  10_19  SW  OUT  = SW_PVCCIN_CPU1_SW3
  25_29  VIN1  IN  = SW_P12V_PVCCIN_CPU1_FLT
  30  VIN2  IN  = SW_P12V_PVCCIN_CPU1_FLT
  31  DNC  TRI  = NC
  32  PHASE  POWER  = SW_PVCCIN_CPU1_BOOTR3
  33  BOOT  POWER  = SW_PVCCIN_CPU1_BOOT3
  34  PWM  IN  = PVCCIN_CPU1_PWM3
  35  EN  IN  = PVCCIN_CPU1_VDD3
  36  TOUT_FLT  OUT  = PVCCIN_CPU1_ATSEN
  37  LSET  OUT  = PVCCIN_CPU1_LSET3
  38  IOUT  OUT  = PVCCIN_CPU1_IMON3
  39  REFIN  IN  = PVCCIN_CPU1_VREF
  40  PGND3  POWER  = GND
  41  GL2  OUT  = NC

PU29  RAA229126GNPHA0  RAA229126GNP#HA0 IC  pkg QFN48_THXT  page 284
  1  PWM0  OUT  = PVCCFA_EHV_FIVRA_CPU1_PWM1
  2  PWM1  OUT  = PVCCFA_EHV_FIVRA_CPU1_PWM2
  3  PWM2  OUT  = PVCCFA_EHV_FIVRA_CPU1_PWM3
  4  PWM3  OUT  = PVCCFA_EHV_FIVRA_CPU1_PWM4
  5  PWM4  OUT  = PVCCIN_CPU1_PWM8
  6  PWM5  OUT  = PVCCIN_CPU1_PWM7
  7  PWM6  OUT  = PVCCIN_CPU1_PWM6
  8  PWM7  OUT  = PVCCIN_CPU1_PWM5
  9  PWM8  OUT  = PVCCIN_CPU1_PWM4
  10  PWM9  OUT  = PVCCIN_CPU1_PWM3
  11  PWM10  OUT  = PVCCIN_CPU1_PWM2
  12  PWM11  OUT  = PVCCIN_CPU1_PWM1
  13  PMSDA  BI  = SMB_DIO_PVCCIN_CPU1
  14  PMSCL  IN  = SMB_CLK_PVCCIN_CPU1
  15  NPMALERT  OUT  = NC_PVCCIN_CPU1_SMB_ALERT
  16  PG0  OUT  = PWRGD_PVCCIN_CPU1_R
  17  EN0  IN  = PVCCIN_CPU1_EN_R
  18  NVRHOT  OUT  = IRQ_PVCCIN_CPU1_VRHOT_N
  19  \npinalert||npsys_crit\  OUT  = PVCCIN_CPU1_PIN_ALERT
  20  PG1  OUT  = PWRGD_PVCCFA_EHV_FIVRA_CPU1_R
  21  SVCLK  IN  = SVID_CLK_PVCCIN_CPU1_R
  22  SVDATA  BI  = SVID_DIO_PVCCIN_CPU1_R
  23  NSVALERT  OUT  = SVID_ALERT_PVCCIN_CPU1_R
  24  EN1  IN  = PVCCFA_EHV_FIVRA_CPU1_EN_R
  25  VSEN0  IN  = SH_PVCCIN_CPU1_R
  26  RGND0  IN  = VSENSE_PVCCIN_CPU1_DN
  27  CS11  IN  = PVCCIN_CPU1_IMON1
  28  CS10  IN  = PVCCIN_CPU1_IMON2
  29  CS9  IN  = PVCCIN_CPU1_IMON3
  30  CS8  IN  = PVCCIN_CPU1_IMON4
  31  CS7  IN  = PVCCIN_CPU1_IMON5
  32  CS6  IN  = PVCCIN_CPU1_IMON6
  33  CS5  IN  = PVCCIN_CPU1_IMON7
  34  CS4  IN  = PVCCIN_CPU1_IMON8
  35  CS3  IN  = PVCCFA_EHV_FIVRA_CPU1_IMON4
  36  CS2  IN  = PVCCFA_EHV_FIVRA_CPU1_IMON3
  37  CS1  IN  = PVCCFA_EHV_FIVRA_CPU1_IMON2
  38  CS0  IN  = PVCCFA_EHV_FIVRA_CPU1_IMON1
  39  RGND1  IN  = VSENSE_PVCCFA_EHV_FIVRA_CPU1_DN
  40  VSEN1  IN  = SH_PVCCFA_EHV_FIVRA_CPU1_R
  41  CFP  OUT  = PVCCIN_CPU1_VR_FAULT
  42  ADDR_CFG  IN  = PVCCIN_CPU1_ADDR
  43  TEMP0  IN  = PVCCIN_CPU1_ATSEN
  44  \temp1||isys\  IN  = PVCCFA_EHV_FIVRA_CPU1_BTSEN
  45  \vmon||iinsen||vsys||isys\  IN  = PVCCIN_CPU1_CSPIN
  46  \vinsen||vsys\  IN  = PVCCIN_CPU1_VIN_CSNIN
  47  VCC  POWER  = PVCCIN_CPU1_VCC
  48  VCCS  POWER  = PVCCIN_CPU1_VREF
  TH  TH_GND  POWER  = GND

PU30_P1_2  ISL99390FRZTR5935  ISL99390FRZ-TR5935 IC  pkg QFN21_6X5XB  page 285
  1  VOS  IN  = PVCCIN_CPU1_VOS2
  2  AGND  POWER  = GND
  3  VCC  POWER  = PVCCIN_CPU1_VDD2
  4  PVCC  POWER  = PVCCIN_CPU1_PVCC
  5  PGND1  POWER  = GND
  6  GL1  OUT  = NC
  7_9-20_24  PGND2  POWER  = GND
  10_19  SW  OUT  = SW_PVCCIN_CPU1_SW2
  25_29  VIN1  IN  = SW_P12V_PVCCIN_CPU1_FLT
  30  VIN2  IN  = SW_P12V_PVCCIN_CPU1_FLT
  31  DNC  TRI  = NC
  32  PHASE  POWER  = SW_PVCCIN_CPU1_BOOTR2
  33  BOOT  POWER  = SW_PVCCIN_CPU1_BOOT2
  34  PWM  IN  = PVCCIN_CPU1_PWM2
  35  EN  IN  = PVCCIN_CPU1_VDD2
  36  TOUT_FLT  OUT  = PVCCIN_CPU1_ATSEN
  37  LSET  OUT  = PVCCIN_CPU1_LSET2
  38  IOUT  OUT  = PVCCIN_CPU1_IMON2
  39  REFIN  IN  = PVCCIN_CPU1_VREF
  40  PGND3  POWER  = GND
  41  GL2  OUT  = NC

PU31_P1_1  ISL99390FRZTR5935  ISL99390FRZ-TR5935 IC  pkg QFN21_6X5XB  page 285
  1  VOS  IN  = PVCCIN_CPU1_VOS1
  2  AGND  POWER  = GND
  3  VCC  POWER  = PVCCIN_CPU1_VDD1
  4  PVCC  POWER  = PVCCIN_CPU1_PVCC
  5  PGND1  POWER  = GND
  6  GL1  OUT  = NC
  7_9-20_24  PGND2  POWER  = GND
  10_19  SW  OUT  = SW_PVCCIN_CPU1_SW1
  25_29  VIN1  IN  = SW_P12V_PVCCIN_CPU1_FLT
  30  VIN2  IN  = SW_P12V_PVCCIN_CPU1_FLT
  31  DNC  TRI  = NC
  32  PHASE  POWER  = SW_PVCCIN_CPU1_BOOTR1
  33  BOOT  POWER  = SW_PVCCIN_CPU1_BOOT1
  34  PWM  IN  = PVCCIN_CPU1_PWM1
  35  EN  IN  = PVCCIN_CPU1_VDD1
  36  TOUT_FLT  OUT  = PVCCIN_CPU1_ATSEN
  37  LSET  OUT  = PVCCIN_CPU1_LSET1
  38  IOUT  OUT  = PVCCIN_CPU1_IMON1
  39  REFIN  IN  = PVCCIN_CPU1_VREF
  40  PGND3  POWER  = GND
  41  GL2  OUT  = NC

PU35  ISL69260IRAZT  ISL69260IRAZ-T IC  pkg QFN40_TH_0-4_5X5XE  page 278
  1  PWM0  OUT  = NC_PVCCD_HV_CPU0_APWM8
  2  PWM1  OUT  = NC_PVCCD_HV_CPU0_APWM7
  3  PWM2  OUT  = NC_PVCCD_HV_CPU0_APWM6
  4  PWM3  OUT  = NC_PVCCD_HV_CPU0_APWM5
  5  PWM4  OUT  = NC_PVCCD_HV_CPU0_APWM4
  6  PWM5  OUT  = NC_PVCCD_HV_CPU0_APWM3
  7  PWM6  OUT  = NC_PVCCD_HV_CPU0_APWM2
  8  PWM7  OUT  = PVCCD_HV_CPU0_APWM1
  9  PMSDA  BI  = SMB_DIO_PVCCD_HV_CPU0
  10  PMSCL  IN  = SMB_CLK_PVCCD_HV_CPU0
  11  \npmalert#\  OUT  = NC_PVCCD_HV_CPU0_SMB_ALERT
  12  PG0  OUT  = PWRGD_PVCCD_HV_CPU0_R
  13  EN0  IN  = PVCCD_HV_CPU0_EN_R
  14  \nvrhot#\  OUT  = IRQ_PVCCD_CPU0_VRHOT_LVC3_R_N
  15  \npinalert#||npsyscrit#\  OUT  = PVCCD_HV_CPU0_PIN_ALT
  16  PG1  OUT  = NC_PVCCD_HV_CPU0_BVR_RDY
  17  SVCLK  IN  = SVID_CLK_PVCCD_HV_CPU0_R
  18  SVDATA  BI  = SVID_DIO_PVCCD_HV_CPU0_R
  19  \nsvalert#\  OUT  = SVID_ALERT_PVCCD_HV_CPU0_R
  20  EN1  IN  = GND
  21  VSEN0  IN  = SH_PVCCD_HV_CPU0_R
  22  RGND0  IN  = VSENSE_PVCCD_HV_CPU0_DN
  23  CS7  IN  = PVCCD_HV_CPU0_ACSP1
  24  CS6  IN  = NC_PVCCD_HV_CPU0_ACSP2
  25  CS5  IN  = NC_PVCCD_HV_CPU0_ACSP3
  26  CS4  IN  = NC_PVCCD_HV_CPU0_ACSP4
  27  CS3  IN  = NC_PVCCD_HV_CPU0_ACSP5
  28  CS2  IN  = NC_PVCCD_HV_CPU0_ACSP6
  29  CS1  IN  = NC_PVCCD_HV_CPU0_ACSP7
  30  CS0  IN  = NC_PVCCD_HV_CPU0_ACSP8
  31  RGND1  IN  = GND
  32  VSEN1  IN  = GND
  33  CFP  OUT  = PVCCD_HV_CPU0_FAULT
  34  ADDR_CFG  IN  = PVCCD_HV_CPU0_ADDR
  35  TEMP0  IN  = PVCCD_HV_CPU0_ATSEN
  36  \temp1||isys\  IN  = PVCCD_HV_CPU0_ISYS_R
  37  \vmon||iinsen||vsys||isys\  IN  = PVCCD_HV_CPU0_ISENSE_P
  38  \vinsen||vsys\  IN  = PVCCD_HV_CPU0_ISENSE_N
  39  VCC  POWER  = PVCCD_HV_CPU0_VCC
  40  VCCS  POWER  = PVCCD_HV_CPU0_VREF
  TH  TH_GND  POWER  = GND

PU36  ISL99390FRZTR5935  ISL99390FRZ-TR5935 IC  pkg QFN21_6X5XB  page 279
  1  VOS  IN  = PVCCD_HV_CPU0_VOS
  2  AGND  POWER  = GND
  3  VCC  POWER  = PVCCD_HV_CPU0_VDD1
  4  PVCC  POWER  = PVCCFA_EHV_CPU0_PVCC
  5  PGND1  POWER  = GND
  6  GL1  OUT  = NC
  7_9-20_24  PGND2  POWER  = GND
  10_19  SW  OUT  = SW_PVCCD_HV_CPU0_SW1
  25_29  VIN1  IN  = SW_P12V_PVCCINFAON_CPU0_FLT
  30  VIN2  IN  = SW_P12V_PVCCINFAON_CPU0_FLT
  31  DNC  TRI  = NC
  32  PHASE  POWER  = SW_PVCCD_HV_CPU0_BOOTR1
  33  BOOT  POWER  = SW_PVCCD_HV_CPU0_BOOT1
  34  PWM  IN  = PVCCD_HV_CPU0_APWM1
  35  EN  IN  = PVCCD_HV_CPU0_VDD1
  36  TOUT_FLT  OUT  = PVCCD_HV_CPU0_ATSEN
  37  LSET  OUT  = PVCCD_HV_CPU0_LSET1
  38  IOUT  OUT  = PVCCD_HV_CPU0_ACSP1
  39  REFIN  IN  = PVCCD_HV_CPU0_VREF
  40  PGND3  POWER  = GND
  41  GL2  OUT  = NC

PU42  RAA2213404GNPHB0  RAA2213404GNP#HB0 IC  pkg PQFN17_TH_5X4  page 276
  1  TMON  OUT  = PVCCFA_EHV_CPU0_BTSEN
  2  \fault#\  OCA  = PVCCFA_EHV_CPU0_FAULT
  3  LGCTRL  IN  = PVCCFA_EHV_CPU0_NC1
  4  VCC  POWER  = PVCCFA_EHV_CPU0_VDD1
  5  GL1  OUT  = PVCCFA_EHV_CPU0_LSET1
  6_7-13_15-29  GND1  POWER  = GND
  8_12  SW  OUT  = SW_PVCCFA_EHV_CPU0_SW1
  16_18-28  VIN  POWER  = SW_P12V_PVCCINFAON_CPU0_FLT
  19  PHASE  POWER  = SW_PVCCFA_EHV_CPU0_BOOTR1
  20  BOOT  POWER  = SW_PVCCFA_EHV_CPU0_BOOT1
  21  PWM  IN  = PVCCFA_EHV_CPU0_BPWM1
  22  NC1  TRI  = PVCCFA_EHV_CPU0_NC2
  23  GND2  POWER  = GND
  24  REFIN  IN  = PVCCINFAON_CPU0_VREF
  25  IMON  OUT  = PVCCFA_EHV_CPU0_BCSP1
  26  GND3  POWER  = GND
  27  GL2  OUT  = NC

PU43_P0_1  ISL99390FRZTR5935  ISL99390FRZ-TR5935 IC  pkg QFN21_6X5XB  page 275
  1  VOS  IN  = PVCCINFAON_CPU0_VOS1
  2  AGND  POWER  = GND
  3  VCC  POWER  = PVCCINFAON_CPU0_VDD1
  4  PVCC  POWER  = PVCCFA_EHV_CPU0_PVCC
  5  PGND1  POWER  = GND
  6  GL1  OUT  = NC
  7_9-20_24  PGND2  POWER  = GND
  10_19  SW  OUT  = SW_PVCCINFAON_CPU0_SW1
  25_29  VIN1  IN  = SW_P12V_PVCCINFAON_CPU0_FLT
  30  VIN2  IN  = SW_P12V_PVCCINFAON_CPU0_FLT
  31  DNC  TRI  = NC
  32  PHASE  POWER  = SW_PVCCINFAON_CPU0_BOOTR1
  33  BOOT  POWER  = SW_PVCCINFAON_CPU0_BOOT1
  34  PWM  IN  = PVCCINFAON_CPU0_APWM1
  35  EN  IN  = PVCCINFAON_CPU0_VDD1
  36  TOUT_FLT  OUT  = PVCCINFAON_CPU0_ATSEN
  37  LSET  OUT  = PVCCINFAON_CPU0_LSET1
  38  IOUT  OUT  = PVCCINFAON_CPU0_ACSP1
  39  REFIN  IN  = PVCCINFAON_CPU0_VREF
  40  PGND3  POWER  = GND
  41  GL2  OUT  = NC

PU44_P0_2  ISL99390FRZTR5935  ISL99390FRZ-TR5935 IC  pkg QFN21_6X5XB  page 275
  1  VOS  IN  = PVCCINFAON_CPU0_VOS2
  2  AGND  POWER  = GND
  3  VCC  POWER  = PVCCINFAON_CPU0_VDD2
  4  PVCC  POWER  = PVCCFA_EHV_CPU0_PVCC
  5  PGND1  POWER  = GND
  6  GL1  OUT  = NC
  7_9-20_24  PGND2  POWER  = GND
  10_19  SW  OUT  = SW_PVCCINFAON_CPU0_SW2
  25_29  VIN1  IN  = SW_P12V_PVCCINFAON_CPU0_FLT
  30  VIN2  IN  = SW_P12V_PVCCINFAON_CPU0_FLT
  31  DNC  TRI  = NC
  32  PHASE  POWER  = SW_PVCCINFAON_CPU0_BOOTR2
  33  BOOT  POWER  = SW_PVCCINFAON_CPU0_BOOT2
  34  PWM  IN  = PVCCINFAON_CPU0_APWM2
  35  EN  IN  = PVCCINFAON_CPU0_VDD2
  36  TOUT_FLT  OUT  = PVCCINFAON_CPU0_ATSEN
  37  LSET  OUT  = PVCCINFAON_CPU0_LSET2
  38  IOUT  OUT  = PVCCINFAON_CPU0_ACSP2
  39  REFIN  IN  = PVCCINFAON_CPU0_VREF
  40  PGND3  POWER  = GND
  41  GL2  OUT  = NC

PU49  RAA2213404GNPHB0  RAA2213404GNP#HB0 IC  pkg PQFN17_TH_5X4  page 294
  1  TMON  OUT  = PVCCFA_EHV_CPU1_BTSEN
  2  \fault#\  OCA  = PVCCFA_EHV_CPU1_FAULT
  3  LGCTRL  IN  = PVCCFA_EHV_CPU1_NC1
  4  VCC  POWER  = PVCCFA_EHV_CPU1_VDD1
  5  GL1  OUT  = PVCCFA_EHV_CPU1_LSET1
  6_7-13_15-29  GND1  POWER  = GND
  8_12  SW  OUT  = SW_PVCCFA_EHV_CPU1_SW1
  16_18-28  VIN  POWER  = SW_P12V_PVCCINFAON_CPU1_FLT
  19  PHASE  POWER  = SW_PVCCFA_EHV_CPU1_BOOTR1
  20  BOOT  POWER  = SW_PVCCFA_EHV_CPU1_BOOT1
  21  PWM  IN  = PVCCFA_EHV_CPU1_BPWM1
  22  NC1  TRI  = PVCCFA_EHV_CPU1_NC2
  23  GND2  POWER  = GND
  24  REFIN  IN  = PVCCINFAON_CPU1_VREF
  25  IMON  OUT  = PVCCFA_EHV_CPU1_BCSP1
  26  GND3  POWER  = GND
  27  GL2  OUT  = NC

PU50_P1_1  ISL99390FRZTR5935  ISL99390FRZ-TR5935 IC  pkg QFN21_6X5XB  page 293
  1  VOS  IN  = PVCCINFAON_CPU1_VOS1
  2  AGND  POWER  = GND
  3  VCC  POWER  = PVCCINFAON_CPU1_VDD1
  4  PVCC  POWER  = PVCCFA_EHV_CPU1_PVCC
  5  PGND1  POWER  = GND
  6  GL1  OUT  = NC
  7_9-20_24  PGND2  POWER  = GND
  10_19  SW  OUT  = SW_PVCCINFAON_CPU1_SW1
  25_29  VIN1  IN  = SW_P12V_PVCCINFAON_CPU1_FLT
  30  VIN2  IN  = SW_P12V_PVCCINFAON_CPU1_FLT
  31  DNC  TRI  = NC
  32  PHASE  POWER  = SW_PVCCINFAON_CPU1_BOOTR1
  33  BOOT  POWER  = SW_PVCCINFAON_CPU1_BOOT1
  34  PWM  IN  = PVCCINFAON_CPU1_APWM1
  35  EN  IN  = PVCCINFAON_CPU1_VDD1
  36  TOUT_FLT  OUT  = PVCCINFAON_CPU1_ATSEN
  37  LSET  OUT  = PVCCINFAON_CPU1_LSET1
  38  IOUT  OUT  = PVCCINFAON_CPU1_ACSP1
  39  REFIN  IN  = PVCCINFAON_CPU1_VREF
  40  PGND3  POWER  = GND
  41  GL2  OUT  = NC
